# S9S_MB_2U (Grand Teton) — schematic netlist excerpt (pin names and nets, part order shuffled) for the footprints in the layout excerpt that follows; sources: Cadence DE-HDL packaged netlist, KiCad conversion of 03242023_DA0F0TMBIJ0_F0T_Motherboard_J_brd_V01_OCP.brd

R4627  Q_RES  0 5% CHIP  pkg 0402LF  page 248 : A = JTAG_BMC_TDI ; B = JTAG_BMC_TDI_R
PC1261  Q_CAP  22UF 16V 20% X6S  pkg C0805  page 299 : A = SW_P12V_PVCCIN_CPU1_FLT ; B = GND
C1992  Q_CAP_DIFFBUS  DIFF BUS_0.22UF 6.3V 20% X6S  pkg C0201  page 181 : \1\ = P3E_PCH_E1S_TX_DN<2> ; \2\ = P3E_PCH_E1S_TX_C_DN<2>

(kicad_pcb
	(version 20260206)
	(generator "pcbnew")
	(generator_version "10.0")
	(general
		(thickness 1.6)
		(legacy_teardrops no)
	)
	(paper "A4")
	(title_block
		(title "03242023_DA0F0TMBIJ0_F0T_Motherboard_J_brd_V01_OCP.brd")
		(comment 1 "Grand Teton / footprints 2969-2971 of 6105")
	)
	(layers
		(0 "F.Cu" signal "TOP")
		(4 "In1.Cu" signal "GND")
		(6 "In2.Cu" signal "IN1")
		(8 "In3.Cu" signal "GND1")
		(10 "In4.Cu" signal "IN2")
		(12 "In5.Cu" signal "GND2")
		(14 "In6.Cu" signal "IN3")
		(16 "In7.Cu" signal "GND3")
		(18 "In8.Cu" signal "VCC")
		(20 "In9.Cu" signal "VCC1")
		(22 "In10.Cu" signal "GND4")
		(24 "In11.Cu" signal "IN4")
		(26 "In12.Cu" signal "GND5")
		(28 "In13.Cu" signal "IN5")
		(30 "In14.Cu" signal "GND6")
		(32 "In15.Cu" signal "IN6")
		(34 "In16.Cu" signal "GND7")
		(2 "B.Cu" signal "BOTTOM")
		(9 "F.Adhes" user "F.Adhesive")
		(11 "B.Adhes" user "B.Adhesive")
		(13 "F.Paste" user "Package Geometry/Pastemask Top")
		(15 "B.Paste" user "Package Geometry/Pastemask Bottom")
		(5 "F.SilkS" user "Ref Des/Silkscreen Top")
		(7 "B.SilkS" user "Ref Des/Silkscreen Bottom")
		(1 "F.Mask" user "Board Geometry/Soldermask Top")
		(3 "B.Mask" user "Board Geometry/Soldermask Bottom")
		(17 "Dwgs.User" user "User.Drawings")
		(19 "Cmts.User" user "User.Comments")
		(21 "Eco1.User" user "User.Eco1")
		(23 "Eco2.User" user "User.Eco2")
		(25 "Edge.Cuts" user "Board Geometry/Outline")
		(27 "Margin" user)
		(31 "F.CrtYd" user "Package Geometry/Place Bound Top")
		(29 "B.CrtYd" user "Package Geometry/Place Bound Bottom")
		(35 "F.Fab" user "Ref Des/Assembly Top")
		(33 "B.Fab" user "Ref Des/Assembly Bottom")
	)
	(footprint ""
		(layer "F.Cu")
		(at 240.854484 -55.612792 180)
		(property "Reference" "C1992"
			(at 0 0 180)
			(layer "F.SilkS")
			(hide yes)
			(effects
				(font
					(size 1.27 1.27)
				)
			)
		)
		(property "Value" ""
			(at 0 0 180)
			(layer "F.Fab")
			(effects
				(font
					(size 1.27 1.27)
				)
			)
		)
		(duplicate_pad_numbers_are_jumpers no)
		(fp_line
			(start 0.299974 0.150114)
			(end -0.299974 0.150114)
			(stroke
				(width 0.1)
				(type default)
			)
			(layer "F.Fab")
		)
		(fp_line
			(start 0.299974 -0.150114)
			(end 0.299974 0.150114)
			(stroke
				(width 0.1)
				(type default)
			)
			(layer "F.Fab")
		)
		(fp_line
			(start -0.299974 0.150114)
			(end -0.299974 -0.150114)
			(stroke
				(width 0.1)
				(type default)
			)
			(layer "F.Fab")
		)
		(fp_line
			(start -0.299974 -0.150114)
			(end 0.299974 -0.150114)
			(stroke
				(width 0.1)
				(type default)
			)
			(layer "F.Fab")
		)
		(pad "1" smd rect
			(at -0.2667 0 180)
			(size 0.3048 0.381)
			(layers "F.Cu" "F.Mask" "F.Paste")
			(net "P3E_PCH_E1S_TX_DN<2>")
		)
		(pad "2" smd rect
			(at 0.2667 0 180)
			(size 0.3048 0.381)
			(layers "F.Cu" "F.Mask" "F.Paste")
			(net "P3E_PCH_E1S_TX_C_DN<2>")
		)
		(zone
			(layer "In1.Cu")
			(hatch none 0.5)
			(connect_pads
				(clearance 0)
			)
			(min_thickness 0.25)
			(keepout
				(tracks not_allowed)
				(vias allowed)
				(pads allowed)
				(copperpour not_allowed)
				(footprints allowed)
			)
			(placement
				(enabled no)
				(sheetname "")
			)
			(fill
				(thermal_gap 0.5)
				(thermal_bridge_width 0.5)
				(island_removal_mode 0)
			)
			(polygon
				(pts
					(arc
						(start 240.714784 -55.853076)
						(mid 240.768666 -55.830758)
						(end 240.790984 -55.776876)
					)
					(arc
						(start 240.790984 -55.446676)
						(mid 240.768666 -55.392794)
						(end 240.714784 -55.370476)
					)
					(arc
						(start 240.460784 -55.370476)
						(mid 240.406902 -55.392794)
						(end 240.384584 -55.446676)
					)
					(arc
						(start 240.384584 -55.776876)
						(mid 240.406902 -55.830758)
						(end 240.460784 -55.853076)
					)
				)
			)
		)
		(zone
			(layer "In1.Cu")
			(hatch none 0.5)
			(connect_pads
				(clearance 0)
			)
			(min_thickness 0.25)
			(keepout
				(tracks not_allowed)
				(vias allowed)
				(pads allowed)
				(copperpour not_allowed)
				(footprints allowed)
			)
			(placement
				(enabled no)
				(sheetname "")
			)
			(fill
				(thermal_gap 0.5)
				(thermal_bridge_width 0.5)
				(island_removal_mode 0)
			)
			(polygon
				(pts
					(arc
						(start 241.248184 -55.853076)
						(mid 241.302066 -55.830758)
						(end 241.324384 -55.776876)
					)
					(arc
						(start 241.324384 -55.446676)
						(mid 241.302066 -55.392794)
						(end 241.248184 -55.370476)
					)
					(arc
						(start 240.994184 -55.370476)
						(mid 240.940302 -55.392794)
						(end 240.917984 -55.446676)
					)
					(arc
						(start 240.917984 -55.776876)
						(mid 240.940302 -55.830758)
						(end 240.994184 -55.853076)
					)
				)
			)
		)
	)
	(footprint ""
		(layer "F.Cu")
		(at 126.385828 -350.780858)
		(property "Reference" "PC1261"
			(at 0 0 0)
			(layer "F.SilkS")
			(hide yes)
			(effects
				(font
					(size 1.27 1.27)
				)
			)
		)
		(property "Value" ""
			(at 0 0 0)
			(layer "F.Fab")
			(effects
				(font
					(size 1.27 1.27)
				)
			)
		)
		(duplicate_pad_numbers_are_jumpers no)
		(fp_line
			(start -1.524 -0.762)
			(end 1.524 -0.762)
			(stroke
				(width 0.1524)
				(type default)
			)
			(layer "F.SilkS")
		)
		(fp_line
			(start -1.524 0.762)
			(end -1.524 -0.762)
			(stroke
				(width 0.1524)
				(type default)
			)
			(layer "F.SilkS")
		)
		(fp_line
			(start 1.524 -0.762)
			(end 1.524 0.762)
			(stroke
				(width 0.1524)
				(type default)
			)
			(layer "F.SilkS")
		)
		(fp_line
			(start 1.524 0.762)
			(end -1.524 0.762)
			(stroke
				(width 0.1524)
				(type default)
			)
			(layer "F.SilkS")
		)
		(fp_line
			(start -1.1049 -0.724916)
			(end -1.1049 0.724916)
			(stroke
				(width 0.1)
				(type default)
			)
			(layer "F.Fab")
		)
		(fp_line
			(start -1.1049 0.724916)
			(end 1.1049 0.724916)
			(stroke
				(width 0.1)
				(type default)
			)
			(layer "F.Fab")
		)
		(fp_line
			(start 1.1049 -0.724916)
			(end -1.1049 -0.724916)
			(stroke
				(width 0.1)
				(type default)
			)
			(layer "F.Fab")
		)
		(fp_line
			(start 1.1049 0.724916)
			(end 1.1049 -0.724916)
			(stroke
				(width 0.1)
				(type default)
			)
			(layer "F.Fab")
		)
		(pad "1" smd rect
			(at -0.889 0 180)
			(size 1.016 1.27)
			(layers "F.Cu" "F.Mask" "F.Paste")
			(net "SW_P12V_PVCCIN_CPU1_FLT")
		)
		(pad "2" smd rect
			(at 0.889 0 180)
			(size 1.016 1.27)
			(layers "F.Cu" "F.Mask" "F.Paste")
			(net "GND")
		)
	)
	(footprint ""
		(layer "F.Cu")
		(at 143.764 -26.126948 180)
		(property "Reference" "R4627"
			(at 0 0 180)
			(layer "F.SilkS")
			(hide yes)
			(effects
				(font
					(size 1.27 1.27)
				)
			)
		)
		(property "Value" ""
			(at 0 0 180)
			(layer "F.Fab")
			(effects
				(font
					(size 1.27 1.27)
				)
			)
		)
		(duplicate_pad_numbers_are_jumpers no)
		(fp_line
			(start 0.7874 0.4064)
			(end -0.7874 0.4064)
			(stroke
				(width 0.1524)
				(type default)
			)
			(layer "F.SilkS")
		)
		(fp_line
			(start 0.7874 -0.4064)
			(end 0.7874 0.4064)
			(stroke
				(width 0.1524)
				(type default)
			)
			(layer "F.SilkS")
		)
		(fp_line
			(start -0.7874 0.4064)
			(end -0.7874 -0.4064)
			(stroke
				(width 0.1524)
				(type default)
			)
			(layer "F.SilkS")
		)
		(fp_line
			(start -0.7874 -0.4064)
			(end 0.7874 -0.4064)
			(stroke
				(width 0.1524)
				(type default)
			)
			(layer "F.SilkS")
		)
		(fp_line
			(start 0.67945 0.3048)
			(end 0.120396 0.3048)
			(stroke
				(width 0.1)
				(type default)
			)
			(layer "F.Fab")
		)
		(fp_line
			(start 0.67945 -0.3048)
			(end 0.67945 0.3048)
			(stroke
				(width 0.1)
				(type default)
			)
			(layer "F.Fab")
		)
		(fp_line
			(start 0.12065 -0.2794)
			(end 0.12065 -0.3048)
			(stroke
				(width 0.1)
				(type default)
			)
			(layer "F.Fab")
		)
		(fp_line
			(start 0.12065 -0.3048)
			(end 0.67945 -0.3048)
			(stroke
				(width 0.1)
				(type default)
			)
			(layer "F.Fab")
		)
		(fp_line
			(start 0.120396 0.3048)
			(end 0.120396 0.2794)
			(stroke
				(width 0.1)
				(type default)
			)
			(layer "F.Fab")
		)
		(fp_line
			(start 0.120396 0.2794)
			(end -0.12065 0.2794)
			(stroke
				(width 0.1)
				(type default)
			)
			(layer "F.Fab")
		)
		(fp_line
			(start -0.12065 0.3048)
			(end -0.67945 0.3048)
			(stroke
				(width 0.1)
				(type default)
			)
			(layer "F.Fab")
		)
		(fp_line
			(start -0.12065 0.2794)
			(end -0.12065 0.3048)
			(stroke
				(width 0.1)
				(type default)
			)
			(layer "F.Fab")
		)
		(fp_line
			(start -0.12065 -0.2794)
			(end 0.12065 -0.2794)
			(stroke
				(width 0.1)
				(type default)
			)
			(layer "F.Fab")
		)
		(fp_line
			(start -0.12065 -0.305054)
			(end -0.12065 -0.2794)
			(stroke
				(width 0.1)
				(type default)
			)
			(layer "F.Fab")
		)
		(fp_line
			(start -0.67945 0.3048)
			(end -0.67945 -0.305054)
			(stroke
				(width 0.1)
				(type default)
			)
			(layer "F.Fab")
		)
		(fp_line
			(start -0.67945 -0.305054)
			(end -0.12065 -0.305054)
			(stroke
				(width 0.1)
				(type default)
			)
			(layer "F.Fab")
		)
		(pad "1" smd circle
			(at -0.40005 0 180)
			(size 0 0)
			(layers "F.Cu" "F.Mask" "F.Paste")
			(net "JTAG_BMC_TDI")
		)
		(pad "2" smd circle
			(at 0.40005 0 180)
			(size 0 0)
			(layers "F.Cu" "F.Mask" "F.Paste")
			(net "JTAG_BMC_TDI_R")
		)
	)
)
